FILE_TYPE = CONNECTIVITY;
{Allegro Design Entry HDL 17.2-2016 S081 (4005846) 1/11/2022}
"PAGE_NUMBER" = 32;
0"NC";
1"GND\g";
2"GND\g";
3"GND\g";
4"GND\g";
5"GND\g";
6"GND\g";
7"GND\g";
8"GND\g";
%"GENOA_SP5"
"34","(-7775,3450)","0","pure_quanta","I13";
;
LOCATION"U25"
$SEC"34"
CDS_SEC"34"
PART_TYPE"SMLF"
MATERIAL"IO"
VALUE"SOCKET6096_13568-001"
PART_NUMBER"DGA^6000030"
NEEDS_NO_SIZE"TRUE"
CDS_LMAN_SYM_OUTLINE"-400,3050,400,-3050"
CDS_LIB"pure_quanta";
"VSS_BV45"
$PN"BV45"2;
"VSS_BV44"
$PN"BV44"2;
"VSS_BV43"
$PN"BV43"2;
"VSS_BV39"
$PN"BV39"2;
"VSS_BV34"
$PN"BV34"2;
"VSS_BV33"
$PN"BV33"2;
"VSS_BV32"
$PN"BV32"2;
"VSS_BV31"
$PN"BV31"2;
"VSS_BV30"
$PN"BV30"2;
"VSS_BV29"
$PN"BV29"2;
"VSS_BV28"
$PN"BV28"2;
"VSS_BV27"
$PN"BV27"2;
"VSS_BV26"
$PN"BV26"2;
"VSS_BV25"
$PN"BV25"2;
"VSS_BV24"
$PN"BV24"2;
"VSS_BV23"
$PN"BV23"2;
"VSS_BV17"
$PN"BV17"2;
"VSS_BV15"
$PN"BV15"2;
"VSS_BV10"
$PN"BV10"2;
"VSS_BV8"
$PN"BV8"2;
"VSS_BV3"
$PN"BV3"2;
"VSS_BU75"
$PN"BU75"2;
"VSS_BU72"
$PN"BU72"2;
"VSS_BU70"
$PN"BU70"2;
"VSS_BU68"
$PN"BU68"2;
"VSS_BU65"
$PN"BU65"2;
"VSS_BU63"
$PN"BU63"2;
"VSS_BU61"
$PN"BU61"2;
"VSS_BU58"
$PN"BU58"2;
"VSS_BU56"
$PN"BU56"2;
"VSS_BU54"
$PN"BU54"2;
"VSS_BU51"
$PN"BU51"2;
"VSS_BU48"
$PN"BU48"2;
"VSS_BU45"
$PN"BU45"2;
"VSS_BU42"
$PN"BU42"2;
"VSS_BU41"
$PN"BU41"2;
"VSS_BU40"
$PN"BU40"2;
"VSS_BU36"
$PN"BU36"2;
"VSS_BU35"
$PN"BU35"2;
"VSS_BU34"
$PN"BU34"2;
"VSS_BU31"
$PN"BU31"2;
"VSS_BU28"
$PN"BU28"2;
"VSS_BU25"
$PN"BU25"2;
"VSS_BU22"
$PN"BU22"2;
"VSS_BU20"
$PN"BU20"2;
"VSS_BU18"
$PN"BU18"2;
"VSS_BU15"
$PN"BU15"2;
"VSS_BU13"
$PN"BU13"2;
"VSS_BU11"
$PN"BU11"2;
"VSS_BU8"
$PN"BU8"2;
"VSS_BU6"
$PN"BU6"2;
"VSS_BU4"
$PN"BU4"2;
"VSS_BU1"
$PN"BU1"2;
"VSS_BT73"
$PN"BT73"2;
"VSS_BT72"
$PN"BT72"2;
"VSS_BT71"
$PN"BT71"2;
"VSS_BT69"
$PN"BT69"2;
"VSS_BT68"
$PN"BT68"2;
"VSS_BT66"
$PN"BT66"2;
"VSS_BT65"
$PN"BT65"2;
"VSS_BT64"
$PN"BT64"2;
"VSS_BT62"
$PN"BT62"2;
"VSS_BT61"
$PN"BT61"2;
"VSS_BT59"
$PN"BT59"2;
"VSS_BT58"
$PN"BT58"2;
"VSS_BT57"
$PN"BT57"2;
"VSS_BT55"
$PN"BT55"2;
"VSS_BT54"
$PN"BT54"2;
"VSS_BT51"
$PN"BT51"2;
"VSS_BT48"
$PN"BT48"2;
"VSS_BT45"
$PN"BT45"2;
"VSS_BT42"
$PN"BT42"2;
"VSS_BT39"
$PN"BT39"2;
"VSS_BT37"
$PN"BT37"2;
"VSS_BT34"
$PN"BT34"2;
"VSS_BT31"
$PN"BT31"2;
"VSS_BT28"
$PN"BT28"2;
"VSS_BT25"
$PN"BT25"2;
"VSS_BT22"
$PN"BT22"2;
"VSS_BT21"
$PN"BT21"2;
"VSS_BT19"
$PN"BT19"2;
"VSS_BT18"
$PN"BT18"2;
"VSS_BT17"
$PN"BT17"2;
"VSS_BT15"
$PN"BT15"2;
"VSS_BT14"
$PN"BT14"2;
"VSS_BT12"
$PN"BT12"2;
"VSS_BT11"
$PN"BT11"2;
"VSS_BT10"
$PN"BT10"2;
"VSS_BT8"
$PN"BT8"2;
"VSS_BT7"
$PN"BT7"2;
"VSS_BT5"
$PN"BT5"2;
"VSS_BT4"
$PN"BT4"2;
"VSS_BT3"
$PN"BT3"2;
"VSS_BR75"
$PN"BR75"2;
"VSS_BR73"
$PN"BR73"2;
"VSS_BR70"
$PN"BR70"2;
"VSS_BR69"
$PN"BR69"2;
"VSS_BR68"
$PN"BR68"2;
"VSS_BR66"
$PN"BR66"2;
"VSS_BR63"
$PN"BR63"2;
"VSS_BR62"
$PN"BR62"2;
"VSS_BR61"
$PN"BR61"2;
"VSS_BR59"
$PN"BR59"2;
"VSS_BR56"
$PN"BR56"2;
"VSS_BR55"
$PN"BR55"2;
"VSS_BR51"
$PN"BR51"2;
"VSS_BR49"
$PN"BR49"2;
"VSS_BR47"
$PN"BR47"2;
"VSS_BR45"
$PN"BR45"2;
"VSS_BR43"
$PN"BR43"2;
"VSS_BR41"
$PN"BR41"2;
"VSS_BR36"
$PN"BR36"2;
"VSS_BR34"
$PN"BR34"2;
"VSS_BR32"
$PN"BR32"2;
"VSS_BR30"
$PN"BR30"2;
"VSS_BR28"
$PN"BR28"2;
"VSS_BR26"
$PN"BR26"2;
"VSS_BR24"
$PN"BR24"1;
"VSS_BR22"
$PN"BR22"1;
"VSS_BR21"
$PN"BR21"1;
"VSS_BR20"
$PN"BR20"1;
"VSS_BR17"
$PN"BR17"1;
"VSS_BR15"
$PN"BR15"1;
"VSS_BR14"
$PN"BR14"1;
"VSS_BR13"
$PN"BR13"1;
"VSS_BR10"
$PN"BR10"1;
"VSS_BR8"
$PN"BR8"1;
"VSS_BR7"
$PN"BR7"1;
"VSS_BR6"
$PN"BR6"1;
"VSS_BR3"
$PN"BR3"1;
"VSS_BR1"
$PN"BR1"1;
"VSS_BP73"
$PN"BP73"1;
"VSS_BP71"
$PN"BP71"1;
"VSS_BP68"
$PN"BP68"1;
"VSS_BP66"
$PN"BP66"1;
"VSS_BP64"
$PN"BP64"1;
"VSS_BP61"
$PN"BP61"1;
"VSS_BP59"
$PN"BP59"1;
"VSS_BP57"
$PN"BP57"1;
"VSS_BP54"
$PN"BP54"1;
"VSS_BP52"
$PN"BP52"1;
"VSS_BP50"
$PN"BP50"1;
"VSS_BP48"
$PN"BP48"1;
"VSS_BP46"
$PN"BP46"1;
"VSS_BP44"
$PN"BP44"1;
"VSS_BP42"
$PN"BP42"1;
"VSS_BP40"
$PN"BP40"1;
"VSS_BP37"
$PN"BP37"1;
"VSS_BP35"
$PN"BP35"1;
"VSS_BP33"
$PN"BP33"1;
"VSS_BP31"
$PN"BP31"1;
"VSS_BP29"
$PN"BP29"1;
"VSS_BP27"
$PN"BP27"1;
"VSS_BP25"
$PN"BP25"1;
"VSS_BP23"
$PN"BP23"1;
"VSS_BP19"
$PN"BP19"1;
"VSS_BP17"
$PN"BP17"1;
"VSS_BP15"
$PN"BP15"1;
"VSS_BP12"
$PN"BP12"1;
"VSS_BP10"
$PN"BP10"1;
"VSS_BP8"
$PN"BP8"1;
"VSS_BP5"
$PN"BP5"1;
"VSS_BP3"
$PN"BP3"1;
"VSS_BN75"
$PN"BN75"1;
"VSS_BN72"
$PN"BN72"1;
"VSS_BN70"
$PN"BN70"1;
"VSS_BN68"
$PN"BN68"1;
"VSS_BN65"
$PN"BN65"1;
"VSS_BN63"
$PN"BN63"1;
"VSS_BN61"
$PN"BN61"1;
"VSS_BN58"
$PN"BN58"1;
"VSS_BN56"
$PN"BN56"1;
"VSS_BN53"
$PN"BN53"1;
"VSS_BN51"
$PN"BN51"1;
"VSS_BN49"
$PN"BN49"1;
"VSS_BN47"
$PN"BN47"1;
"VSS_BN45"
$PN"BN45"1;
"VSS_BN43"
$PN"BN43"1;
"VSS_BN41"
$PN"BN41"1;
"VSS_BN36"
$PN"BN36"1;
"VSS_BN34"
$PN"BN34"1;
"VSS_BN32"
$PN"BN32"1;
"VSS_BN30"
$PN"BN30"1;
"VSS_BN28"
$PN"BN28"1;
"VSS_BN26"
$PN"BN26"1;
"VSS_BN24"
$PN"BN24"1;
"VSS_BN22"
$PN"BN22"1;
"VSS_BN20"
$PN"BN20"1;
"VSS_BN18"
$PN"BN18"1;
"VSS_BN15"
$PN"BN15"1;
"VSS_BN13"
$PN"BN13"1;
"VSS_BN11"
$PN"BN11"1;
"VSS_BN8"
$PN"BN8"1;
"VSS_BN6"
$PN"BN6"1;
"VSS_BN4"
$PN"BN4"1;
"VSS_BN1"
$PN"BN1"1;
"VSS_BM73"
$PN"BM73"1;
"VSS_BM68"
$PN"BM68"1;
"VSS_BM66"
$PN"BM66"1;
"VSS_BM61"
$PN"BM61"1;
"VSS_BM59"
$PN"BM59"1;
"VSS_BM54"
$PN"BM54"1;
"VSS_BM52"
$PN"BM52"1;
"VSS_BM50"
$PN"BM50"1;
"VSS_BM48"
$PN"BM48"1;
"VSS_BM46"
$PN"BM46"1;
"VSS_BM44"
$PN"BM44"1;
"VSS_BM42"
$PN"BM42"1;
"VSS_BM40"
$PN"BM40"1;
"VSS_BM37"
$PN"BM37"1;
"VSS_BM35"
$PN"BM35"1;
"VSS_BM33"
$PN"BM33"1;
"VSS_BM31"
$PN"BM31"1;
"VSS_BM29"
$PN"BM29"1;
"VSS_BM27"
$PN"BM27"1;
"VSS_BM25"
$PN"BM25"1;
"VSS_BM23"
$PN"BM23"1;
"VSS_BM17"
$PN"BM17"1;
"VSS_BM15"
$PN"BM15"1;
"VSS_BM10"
$PN"BM10"1;
"VSS_BM8"
$PN"BM8"1;
"VSS_BM3"
$PN"BM3"1;
"VSS_BL75"
$PN"BL75"1;
"VSS_BL72"
$PN"BL72"1;
"VSS_BL70"
$PN"BL70"1;
"VSS_BL68"
$PN"BL68"1;
"VSS_BL65"
$PN"BL65"1;
"VSS_BL63"
$PN"BL63"1;
"VSS_BL61"
$PN"BL61"1;
"VSS_BL58"
$PN"BL58"1;
"VSS_BL56"
$PN"BL56"1;
"VSS_BL53"
$PN"BL53"1;
"VSS_BL51"
$PN"BL51"1;
"VSS_BL49"
$PN"BL49"1;
"VSS_BL28"
$PN"BL28"1;
"VSS_BL26"
$PN"BL26"1;
"VSS_BV37"
$PN"BV37"2;
%"GENOA_SP5"
"37","(-5750,3450)","0","pure_quanta","I14";
;
LOCATION"U25"
$SEC"37"
CDS_SEC"37"
PART_TYPE"SMLF"
MATERIAL"IO"
VALUE"SOCKET6096_13568-001"
PART_NUMBER"DGA^6000030"
NEEDS_NO_SIZE"TRUE"
CDS_LMAN_SYM_OUTLINE"-400,3050,400,-3050"
CDS_LIB"pure_quanta";
"VSS_CF33"
$PN"CF33"4;
"VSS_CF32"
$PN"CF32"4;
"VSS_CF31"
$PN"CF31"4;
"VSS_CF30"
$PN"CF30"4;
"VSS_CF29"
$PN"CF29"4;
"VSS_CF28"
$PN"CF28"4;
"VSS_CF27"
$PN"CF27"4;
"VSS_CF26"
$PN"CF26"4;
"VSS_CF25"
$PN"CF25"4;
"VSS_CF24"
$PN"CF24"4;
"VSS_CF23"
$PN"CF23"4;
"VSS_CF19"
$PN"CF19"4;
"VSS_CF17"
$PN"CF17"4;
"VSS_CF15"
$PN"CF15"4;
"VSS_CF12"
$PN"CF12"4;
"VSS_CF10"
$PN"CF10"4;
"VSS_CF8"
$PN"CF8"4;
"VSS_CF5"
$PN"CF5"4;
"VSS_CF3"
$PN"CF3"4;
"VSS_CE75"
$PN"CE75"4;
"VSS_CE72"
$PN"CE72"4;
"VSS_CE70"
$PN"CE70"4;
"VSS_CE68"
$PN"CE68"4;
"VSS_CE65"
$PN"CE65"4;
"VSS_CE63"
$PN"CE63"4;
"VSS_CE61"
$PN"CE61"4;
"VSS_CE58"
$PN"CE58"4;
"VSS_CE56"
$PN"CE56"4;
"VSS_CE54"
$PN"CE54"4;
"VSS_CE51"
$PN"CE51"4;
"VSS_CE48"
$PN"CE48"4;
"VSS_CE45"
$PN"CE45"4;
"VSS_CE42"
$PN"CE42"4;
"VSS_CE41"
$PN"CE41"4;
"VSS_CE40"
$PN"CE40"4;
"VSS_CE36"
$PN"CE36"4;
"VSS_CE35"
$PN"CE35"4;
"VSS_CE34"
$PN"CE34"4;
"VSS_CE31"
$PN"CE31"4;
"VSS_CE28"
$PN"CE28"4;
"VSS_CE25"
$PN"CE25"4;
"VSS_CE22"
$PN"CE22"4;
"VSS_CE20"
$PN"CE20"4;
"VSS_CE18"
$PN"CE18"4;
"VSS_CE15"
$PN"CE15"4;
"VSS_CE13"
$PN"CE13"4;
"VSS_CE11"
$PN"CE11"4;
"VSS_CE8"
$PN"CE8"4;
"VSS_CE6"
$PN"CE6"4;
"VSS_CE4"
$PN"CE4"4;
"VSS_CE1"
$PN"CE1"4;
"VSS_CD73"
$PN"CD73"4;
"VSS_CD68"
$PN"CD68"4;
"VSS_CD66"
$PN"CD66"4;
"VSS_CD61"
$PN"CD61"4;
"VSS_CD59"
$PN"CD59"4;
"VSS_CD54"
$PN"CD54"4;
"VSS_CD51"
$PN"CD51"4;
"VSS_CD48"
$PN"CD48"4;
"VSS_CD45"
$PN"CD45"4;
"VSS_CD42"
$PN"CD42"4;
"VSS_CD39"
$PN"CD39"4;
"VSS_CD37"
$PN"CD37"4;
"VSS_CD34"
$PN"CD34"4;
"VSS_CD31"
$PN"CD31"4;
"VSS_CD28"
$PN"CD28"4;
"VSS_CD25"
$PN"CD25"4;
"VSS_CD22"
$PN"CD22"4;
"VSS_CD17"
$PN"CD17"4;
"VSS_CD15"
$PN"CD15"4;
"VSS_CD10"
$PN"CD10"4;
"VSS_CD8"
$PN"CD8"4;
"VSS_CD3"
$PN"CD3"4;
"VSS_CC75"
$PN"CC75"4;
"VSS_CC72"
$PN"CC72"4;
"VSS_CC70"
$PN"CC70"4;
"VSS_CC68"
$PN"CC68"4;
"VSS_CC65"
$PN"CC65"4;
"VSS_CC63"
$PN"CC63"4;
"VSS_CC61"
$PN"CC61"4;
"VSS_CC58"
$PN"CC58"4;
"VSS_CC56"
$PN"CC56"4;
"VSS_CC54"
$PN"CC54"4;
"VSS_CC51"
$PN"CC51"4;
"VSS_CC48"
$PN"CC48"4;
"VSS_CC45"
$PN"CC45"4;
"VSS_CC42"
$PN"CC42"4;
"VSS_CC34"
$PN"CC34"4;
"VSS_CC31"
$PN"CC31"4;
"VSS_CC28"
$PN"CC28"4;
"VSS_CC25"
$PN"CC25"4;
"VSS_CC20"
$PN"CC20"4;
"VSS_CC18"
$PN"CC18"4;
"VSS_CC15"
$PN"CC15"4;
"VSS_CC13"
$PN"CC13"4;
"VSS_CC11"
$PN"CC11"4;
"VSS_CC8"
$PN"CC8"4;
"VSS_CC6"
$PN"CC6"4;
"VSS_CC4"
$PN"CC4"4;
"VSS_CC1"
$PN"CC1"4;
"VSS_CB73"
$PN"CB73"4;
"VSS_CB71"
$PN"CB71"4;
"VSS_CB68"
$PN"CB68"4;
"VSS_CB66"
$PN"CB66"4;
"VSS_CB64"
$PN"CB64"4;
"VSS_CB61"
$PN"CB61"4;
"VSS_CB59"
$PN"CB59"4;
"VSS_CB57"
$PN"CB57"4;
"VSS_CB53"
$PN"CB53"4;
"VSS_CB52"
$PN"CB52"4;
"VSS_CB51"
$PN"CB51"4;
"VSS_CB50"
$PN"CB50"4;
"VSS_CB49"
$PN"CB49"4;
"VSS_CB48"
$PN"CB48"4;
"VSS_CB47"
$PN"CB47"4;
"VSS_CB46"
$PN"CB46"4;
"VSS_CB45"
$PN"CB45"4;
"VSS_CB43"
$PN"CB43"3;
"VSS_CB42"
$PN"CB42"3;
"VSS_CB39"
$PN"CB39"3;
"VSS_CB37"
$PN"CB37"3;
"VSS_CB34"
$PN"CB34"3;
"VSS_CB33"
$PN"CB33"3;
"VSS_CB32"
$PN"CB32"3;
"VSS_CB31"
$PN"CB31"3;
"VSS_CB30"
$PN"CB30"3;
"VSS_CB29"
$PN"CB29"3;
"VSS_CB28"
$PN"CB28"3;
"VSS_CB27"
$PN"CB27"3;
"VSS_CB26"
$PN"CB26"3;
"VSS_CB25"
$PN"CB25"3;
"VSS_CB24"
$PN"CB24"3;
"VSS_CB23"
$PN"CB23"3;
"VSS_CB19"
$PN"CB19"3;
"VSS_CB17"
$PN"CB17"3;
"VSS_CB15"
$PN"CB15"3;
"VSS_CB12"
$PN"CB12"3;
"VSS_CB10"
$PN"CB10"3;
"VSS_CB8"
$PN"CB8"3;
"VSS_CB5"
$PN"CB5"3;
"VSS_CB3"
$PN"CB3"3;
"VSS_CA75"
$PN"CA75"3;
"VSS_CA70"
$PN"CA70"3;
"VSS_CA68"
$PN"CA68"3;
"VSS_CA63"
$PN"CA63"3;
"VSS_CA61"
$PN"CA61"3;
"VSS_CA56"
$PN"CA56"3;
"VSS_CA54"
$PN"CA54"3;
"VSS_CA51"
$PN"CA51"3;
"VSS_CA48"
$PN"CA48"3;
"VSS_CA45"
$PN"CA45"3;
"VSS_CA42"
$PN"CA42"3;
"VSS_CA41"
$PN"CA41"3;
"VSS_CA40"
$PN"CA40"3;
"VSS_CA36"
$PN"CA36"3;
"VSS_CA35"
$PN"CA35"3;
"VSS_CA34"
$PN"CA34"3;
"VSS_CA31"
$PN"CA31"3;
"VSS_CA28"
$PN"CA28"3;
"VSS_CA25"
$PN"CA25"3;
"VSS_CA22"
$PN"CA22"3;
"VSS_CA20"
$PN"CA20"3;
"VSS_CA15"
$PN"CA15"3;
"VSS_CA13"
$PN"CA13"3;
"VSS_CA8"
$PN"CA8"3;
"VSS_CA6"
$PN"CA6"3;
"VSS_CA1"
$PN"CA1"3;
"VSS_BY73"
$PN"BY73"3;
"VSS_BY71"
$PN"BY71"3;
"VSS_BY68"
$PN"BY68"3;
"VSS_BY66"
$PN"BY66"3;
"VSS_BY64"
$PN"BY64"3;
"VSS_BY61"
$PN"BY61"3;
"VSS_BY59"
$PN"BY59"3;
"VSS_BY57"
$PN"BY57"3;
"VSS_BY54"
$PN"BY54"3;
"VSS_BY51"
$PN"BY51"3;
"VSS_BY48"
$PN"BY48"3;
"VSS_BY45"
$PN"BY45"3;
"VSS_BY42"
$PN"BY42"3;
"VSS_BY39"
$PN"BY39"3;
"VSS_BY37"
$PN"BY37"3;
"VSS_BY34"
$PN"BY34"3;
"VSS_BY31"
$PN"BY31"3;
"VSS_BY28"
$PN"BY28"3;
"VSS_BY25"
$PN"BY25"3;
"VSS_BY22"
$PN"BY22"3;
"VSS_BY19"
$PN"BY19"3;
"VSS_BY17"
$PN"BY17"3;
"VSS_BY15"
$PN"BY15"3;
"VSS_BY12"
$PN"BY12"3;
"VSS_BY10"
$PN"BY10"3;
"VSS_BY8"
$PN"BY8"3;
"VSS_BY5"
$PN"BY5"3;
"VSS_BY3"
$PN"BY3"3;
"VSS_BW75"
$PN"BW75"3;
"VSS_BW72"
$PN"BW72"3;
"VSS_BW70"
$PN"BW70"3;
"VSS_BW68"
$PN"BW68"3;
"VSS_BW65"
$PN"BW65"3;
"VSS_BW63"
$PN"BW63"3;
"VSS_BW61"
$PN"BW61"3;
"VSS_BW58"
$PN"BW58"3;
"VSS_BW56"
$PN"BW56"3;
"VSS_BW54"
$PN"BW54"3;
"VSS_BW51"
$PN"BW51"3;
"VSS_BW48"
$PN"BW48"3;
"VSS_BW45"
$PN"BW45"3;
"VSS_BW42"
$PN"BW42"3;
"VSS_BW34"
$PN"BW34"3;
"VSS_BW31"
$PN"BW31"3;
"VSS_BW28"
$PN"BW28"3;
"VSS_BW22"
$PN"BW22"3;
"VSS_BW20"
$PN"BW20"3;
"VSS_BW18"
$PN"BW18"3;
"VSS_BW15"
$PN"BW15"3;
"VSS_BW13"
$PN"BW13"3;
"VSS_BW11"
$PN"BW11"3;
"VSS_BW8"
$PN"BW8"3;
"VSS_BW6"
$PN"BW6"3;
"VSS_BW4"
$PN"BW4"3;
"VSS_BW1"
$PN"BW1"3;
"VSS_BV73"
$PN"BV73"3;
"VSS_BV68"
$PN"BV68"3;
"VSS_BV66"
$PN"BV66"3;
"VSS_BV61"
$PN"BV61"3;
"VSS_BV59"
$PN"BV59"3;
"VSS_BV53"
$PN"BV53"3;
"VSS_BV52"
$PN"BV52"3;
"VSS_BV51"
$PN"BV51"3;
"VSS_BV50"
$PN"BV50"3;
"VSS_BV49"
$PN"BV49"3;
"VSS_BV48"
$PN"BV48"3;
"VSS_BV47"
$PN"BV47"3;
"VSS_BV46"
$PN"BV46"3;
%"GENOA_SP5"
"38","(-3675,3425)","0","pure_quanta","I15";
;
LOCATION"U25"
$SEC"38"
CDS_SEC"38"
PART_TYPE"SMLF"
MATERIAL"IO"
VALUE"SOCKET6096_13568-001"
PART_NUMBER"DGA^6000030"
NEEDS_NO_SIZE"TRUE"
CDS_LMAN_SYM_OUTLINE"-400,3050,400,-3050"
CDS_LIB"pure_quanta";
"VSS_CP19"
$PN"CP19"6;
"VSS_CP17"
$PN"CP17"6;
"VSS_CP15"
$PN"CP15"6;
"VSS_CP12"
$PN"CP12"6;
"VSS_CP10"
$PN"CP10"6;
"VSS_CP8"
$PN"CP8"6;
"VSS_CP5"
$PN"CP5"6;
"VSS_CP3"
$PN"CP3"6;
"VSS_CN75"
$PN"CN75"6;
"VSS_CN70"
$PN"CN70"6;
"VSS_CN68"
$PN"CN68"6;
"VSS_CN63"
$PN"CN63"6;
"VSS_CN61"
$PN"CN61"6;
"VSS_CN51"
$PN"CN51"6;
"VSS_CN48"
$PN"CN48"6;
"VSS_CN45"
$PN"CN45"6;
"VSS_CN42"
$PN"CN42"6;
"VSS_CN34"
$PN"CN34"6;
"VSS_CN31"
$PN"CN31"6;
"VSS_CN28"
$PN"CN28"6;
"VSS_CN25"
$PN"CN25"6;
"VSS_CN15"
$PN"CN15"6;
"VSS_CN13"
$PN"CN13"6;
"VSS_CN8"
$PN"CN8"6;
"VSS_CN6"
$PN"CN6"6;
"VSS_CN1"
$PN"CN1"6;
"VSS_CM73"
$PN"CM73"6;
"VSS_CM71"
$PN"CM71"6;
"VSS_CM68"
$PN"CM68"6;
"VSS_CM59"
$PN"CM59"6;
"VSS_CM57"
$PN"CM57"6;
"VSS_CM53"
$PN"CM53"6;
"VSS_CM52"
$PN"CM52"6;
"VSS_CM51"
$PN"CM51"6;
"VSS_CM49"
$PN"CM49"6;
"VSS_CM48"
$PN"CM48"6;
"VSS_CM47"
$PN"CM47"6;
"VSS_CM46"
$PN"CM46"6;
"VSS_CM45"
$PN"CM45"6;
"VSS_CM44"
$PN"CM44"6;
"VSS_CM33"
$PN"CM33"6;
"VSS_CM32"
$PN"CM32"6;
"VSS_CM31"
$PN"CM31"6;
"VSS_CM30"
$PN"CM30"6;
"VSS_CM29"
$PN"CM29"6;
"VSS_CM28"
$PN"CM28"6;
"VSS_CM23"
$PN"CM23"6;
"VSS_CM19"
$PN"CM19"6;
"VSS_CM17"
$PN"CM17"6;
"VSS_CM15"
$PN"CM15"6;
"VSS_CM12"
$PN"CM12"6;
"VSS_CM10"
$PN"CM10"6;
"VSS_CM8"
$PN"CM8"6;
"VSS_CL72"
$PN"CL72"6;
"VSS_CL70"
$PN"CL70"6;
"VSS_CL68"
$PN"CL68"6;
"VSS_CL65"
$PN"CL65"6;
"VSS_CL63"
$PN"CL63"6;
"VSS_CL61"
$PN"CL61"6;
"VSS_CL58"
$PN"CL58"6;
"VSS_CL56"
$PN"CL56"6;
"VSS_CL48"
$PN"CL48"6;
"VSS_CL45"
$PN"CL45"6;
"VSS_CL42"
$PN"CL42"6;
"VSS_CL41"
$PN"CL41"6;
"VSS_CL40"
$PN"CL40"6;
"VSS_CL36"
$PN"CL36"6;
"VSS_CL35"
$PN"CL35"6;
"VSS_CL34"
$PN"CL34"6;
"VSS_CL31"
$PN"CL31"6;
"VSS_CL25"
$PN"CL25"6;
"VSS_CL22"
$PN"CL22"6;
"VSS_CL20"
$PN"CL20"6;
"VSS_CL18"
$PN"CL18"6;
"VSS_CL15"
$PN"CL15"6;
"VSS_CL13"
$PN"CL13"6;
"VSS_CL11"
$PN"CL11"6;
"VSS_CL8"
$PN"CL8"6;
"VSS_CL6"
$PN"CL6"6;
"VSS_CL4"
$PN"CL4"6;
"VSS_CL1"
$PN"CL1"6;
"VSS_CK73"
$PN"CK73"6;
"VSS_CK68"
$PN"CK68"6;
"VSS_CK66"
$PN"CK66"6;
"VSS_CK61"
$PN"CK61"6;
"VSS_CK59"
$PN"CK59"6;
"VSS_CK54"
$PN"CK54"6;
"VSS_CK53"
$PN"CK53"6;
"VSS_CK52"
$PN"CK52"6;
"VSS_CK51"
$PN"CK51"6;
"VSS_CK50"
$PN"CK50"6;
"VSS_CK49"
$PN"CK49"6;
"VSS_CK48"
$PN"CK48"6;
"VSS_CK45"
$PN"CK45"6;
"VSS_CK44"
$PN"CK44"6;
"VSS_CK43"
$PN"CK43"6;
"VSS_CK42"
$PN"CK42"5;
"VSS_CK39"
$PN"CK39"5;
"VSS_CK37"
$PN"CK37"5;
"VSS_CK34"
$PN"CK34"5;
"VSS_CK32"
$PN"CK32"5;
"VSS_CK28"
$PN"CK28"5;
"VSS_CK27"
$PN"CK27"5;
"VSS_CK26"
$PN"CK26"5;
"VSS_CK25"
$PN"CK25"5;
"VSS_CK24"
$PN"CK24"5;
"VSS_CK23"
$PN"CK23"5;
"VSS_CK22"
$PN"CK22"5;
"VSS_CK8"
$PN"CK8"5;
"VSS_CK3"
$PN"CK3"5;
"VSS_CJ75"
$PN"CJ75"5;
"VSS_CJ72"
$PN"CJ72"5;
"VSS_CJ70"
$PN"CJ70"5;
"VSS_CJ68"
$PN"CJ68"5;
"VSS_CJ65"
$PN"CJ65"5;
"VSS_CJ56"
$PN"CJ56"5;
"VSS_CJ45"
$PN"CJ45"5;
"VSS_CJ42"
$PN"CJ42"5;
"VSS_CJ41"
$PN"CJ41"5;
"VSS_CJ40"
$PN"CJ40"5;
"VSS_CJ36"
$PN"CJ36"5;
"VSS_CJ35"
$PN"CJ35"5;
"VSS_CJ18"
$PN"CJ18"5;
"VSS_CJ15"
$PN"CJ15"5;
"VSS_CJ13"
$PN"CJ13"5;
"VSS_CJ11"
$PN"CJ11"5;
"VSS_CJ8"
$PN"CJ8"5;
"VSS_CJ6"
$PN"CJ6"5;
"VSS_CH66"
$PN"CH66"5;
"VSS_CH64"
$PN"CH64"5;
"VSS_CH61"
$PN"CH61"5;
"VSS_CH59"
$PN"CH59"5;
"VSS_CH57"
$PN"CH57"5;
"VSS_CH54"
$PN"CH54"5;
"VSS_CH37"
$PN"CH37"5;
"VSS_CH34"
$PN"CH34"5;
"VSS_CH31"
$PN"CH31"5;
"VSS_CH28"
$PN"CH28"5;
"VSS_CH25"
$PN"CH25"5;
"VSS_CH22"
$PN"CH22"5;
"VSS_CH8"
$PN"CH8"5;
"VSS_CH5"
$PN"CH5"5;
"VSS_CH3"
$PN"CH3"5;
"VSS_CG75"
$PN"CG75"5;
"VSS_CG70"
$PN"CG70"5;
"VSS_CG68"
$PN"CG68"5;
"VSS_CG63"
$PN"CG63"5;
"VSS_CG61"
$PN"CG61"5;
"VSS_CG56"
$PN"CG56"5;
"VSS_CG54"
$PN"CG54"5;
"VSS_CG51"
$PN"CG51"5;
"VSS_CG48"
$PN"CG48"5;
"VSS_CG45"
$PN"CG45"5;
"VSS_CG34"
$PN"CG34"5;
"VSS_CG31"
$PN"CG31"5;
"VSS_CG28"
$PN"CG28"5;
"VSS_CG25"
$PN"CG25"5;
"VSS_CG22"
$PN"CG22"5;
"VSS_CG20"
$PN"CG20"5;
"VSS_CG15"
$PN"CG15"5;
"VSS_CG13"
$PN"CG13"5;
"VSS_CG8"
$PN"CG8"5;
"VSS_CG6"
$PN"CG6"5;
"VSS_CG1"
$PN"CG1"5;
"VSS_CF73"
$PN"CF73"5;
"VSS_CF71"
$PN"CF71"5;
"VSS_CF68"
$PN"CF68"5;
"VSS_CF66"
$PN"CF66"5;
"VSS_CF64"
$PN"CF64"5;
"VSS_CF61"
$PN"CF61"5;
"VSS_CF59"
$PN"CF59"5;
"VSS_CF57"
$PN"CF57"5;
"VSS_CF53"
$PN"CF53"5;
"VSS_CF52"
$PN"CF52"5;
"VSS_CF51"
$PN"CF51"5;
"VSS_CF50"
$PN"CF50"5;
"VSS_CF49"
$PN"CF49"5;
"VSS_CF48"
$PN"CF48"5;
"VSS_CF47"
$PN"CF47"5;
"VSS_CF45"
$PN"CF45"5;
"VSS_CF44"
$PN"CF44"5;
"VSS_CF43"
$PN"CF43"5;
"VSS_CF42"
$PN"CF42"5;
"VSS_CF39"
$PN"CF39"5;
"VSS_CF37"
$PN"CF37"5;
"VSS_CF34"
$PN"CF34"5;
"VSS_CH19"
$PN"CH19"5;
"VSS_CH51"
$PN"CH51"5;
"VSS_CJ4"
$PN"CJ4"5;
"VSS_CL28"
$PN"CL28"6;
"VSS_CL54"
$PN"CL54"6;
"VSS_CM5"
$PN"CM5"6;
"VSS_CM27"
$PN"CM27"6;
"VSS_CM43"
$PN"CM43"6;
"VSS_CH17"
$PN"CH17"5;
"VSS_CH48"
$PN"CH48"5;
"VSS_CJ1"
$PN"CJ1"5;
"VSS_CJ34"
$PN"CJ34"5;
"VSS_CL51"
$PN"CL51"6;
"VSS_CM3"
$PN"CM3"6;
"VSS_CM26"
$PN"CM26"6;
"VSS_CM42"
$PN"CM42"6;
"VSS_CH15"
$PN"CH15"5;
"VSS_CH45"
$PN"CH45"5;
"VSS_CH73"
$PN"CH73"5;
"VSS_CJ31"
$PN"CJ31"5;
"VSS_CJ63"
$PN"CJ63"5;
"VSS_CL75"
$PN"CL75"6;
"VSS_CM25"
$PN"CM25"6;
"VSS_CM39"
$PN"CM39"6;
"VSS_CM66"
$PN"CM66"6;
"VSS_CH12"
$PN"CH12"5;
"VSS_CH42"
$PN"CH42"5;
"VSS_CH71"
$PN"CH71"5;
"VSS_CJ23"
$PN"CJ23"5;
"VSS_CJ61"
$PN"CJ61"5;
"VSS_CK17"
$PN"CK17"5;
"VSS_CM24"
$PN"CM24"6;
"VSS_CM37"
$PN"CM37"6;
"VSS_CM64"
$PN"CM64"6;
"VSS_CN22"
$PN"CN22"6;
"VSS_CH10"
$PN"CH10"5;
"VSS_CH39"
$PN"CH39"5;
"VSS_CH68"
$PN"CH68"5;
"VSS_CJ20"
$PN"CJ20"5;
"VSS_CJ58"
$PN"CJ58"5;
"VSS_CK15"
$PN"CK15"5;
"VSS_CK33"
$PN"CK33"5;
"VSS_CM34"
$PN"CM34"6;
"VSS_CM61"
$PN"CM61"6;
"VSS_CN20"
$PN"CN20"6;
"VSS_CN56"
$PN"CN56"6;
%"GENOA_SP5"
"39","(-1600,3450)","0","pure_quanta","I16";
;
LOCATION"U25"
$SEC"39"
CDS_SEC"39"
PART_TYPE"SMLF"
MATERIAL"IO"
VALUE"SOCKET6096_13568-001"
PART_NUMBER"DGA^6000030"
NEEDS_NO_SIZE"TRUE"
CDS_LMAN_SYM_OUTLINE"-400,3050,400,-3050"
CDS_LIB"pure_quanta";
"VSS_DA70"
$PN"DA70"7;
"VSS_DA68"
$PN"DA68"7;
"VSS_DA65"
$PN"DA65"7;
"VSS_DA63"
$PN"DA63"7;
"VSS_DA61"
$PN"DA61"7;
"VSS_DA58"
$PN"DA58"7;
"VSS_DA42"
$PN"DA42"7;
"VSS_DA34"
$PN"DA34"7;
"VSS_DA31"
$PN"DA31"7;
"VSS_DA28"
$PN"DA28"7;
"VSS_DA25"
$PN"DA25"7;
"VSS_DA22"
$PN"DA22"7;
"VSS_DA11"
$PN"DA11"7;
"VSS_DA8"
$PN"DA8"7;
"VSS_DA6"
$PN"DA6"7;
"VSS_DA4"
$PN"DA4"7;
"VSS_DA1"
$PN"DA1"7;
"VSS_CY73"
$PN"CY73"7;
"VSS_CY71"
$PN"CY71"7;
"VSS_CY61"
$PN"CY61"7;
"VSS_CY59"
$PN"CY59"7;
"VSS_CY53"
$PN"CY53"7;
"VSS_CY52"
$PN"CY52"7;
"VSS_CY51"
$PN"CY51"7;
"VSS_CY50"
$PN"CY50"7;
"VSS_CY49"
$PN"CY49"7;
"VSS_CY46"
$PN"CY46"7;
"VSS_CY45"
$PN"CY45"7;
"VSS_CY44"
$PN"CY44"7;
"VSS_CY43"
$PN"CY43"7;
"VSS_CY42"
$PN"CY42"7;
"VSS_CY39"
$PN"CY39"7;
"VSS_CY37"
$PN"CY37"7;
"VSS_CY34"
$PN"CY34"7;
"VSS_CY33"
$PN"CY33"7;
"VSS_CY31"
$PN"CY31"7;
"VSS_CY30"
$PN"CY30"7;
"VSS_CY29"
$PN"CY29"7;
"VSS_CY28"
$PN"CY28"7;
"VSS_CY27"
$PN"CY27"7;
"VSS_CY26"
$PN"CY26"7;
"VSS_CY25"
$PN"CY25"7;
"VSS_CY24"
$PN"CY24"7;
"VSS_CY23"
$PN"CY23"7;
"VSS_CY19"
$PN"CY19"7;
"VSS_CY17"
$PN"CY17"7;
"VSS_CY15"
$PN"CY15"7;
"VSS_CY12"
$PN"CY12"7;
"VSS_CY10"
$PN"CY10"7;
"VSS_CY8"
$PN"CY8"7;
"VSS_CY5"
$PN"CY5"7;
"VSS_CY3"
$PN"CY3"7;
"VSS_CW75"
$PN"CW75"7;
"VSS_CW70"
$PN"CW70"7;
"VSS_CW68"
$PN"CW68"7;
"VSS_CW63"
$PN"CW63"7;
"VSS_CW61"
$PN"CW61"7;
"VSS_CW56"
$PN"CW56"7;
"VSS_CW54"
$PN"CW54"7;
"VSS_CW51"
$PN"CW51"7;
"VSS_CW48"
$PN"CW48"7;
"VSS_CW45"
$PN"CW45"7;
"VSS_CW42"
$PN"CW42"7;
"VSS_CW41"
$PN"CW41"7;
"VSS_CW40"
$PN"CW40"7;
"VSS_CW36"
$PN"CW36"7;
"VSS_CW35"
$PN"CW35"7;
"VSS_CW20"
$PN"CW20"7;
"VSS_CW15"
$PN"CW15"7;
"VSS_CW13"
$PN"CW13"7;
"VSS_CW8"
$PN"CW8"7;
"VSS_CW6"
$PN"CW6"7;
"VSS_CW1"
$PN"CW1"7;
"VSS_CV61"
$PN"CV61"7;
"VSS_CV59"
$PN"CV59"7;
"VSS_CV57"
$PN"CV57"7;
"VSS_CV54"
$PN"CV54"7;
"VSS_CV51"
$PN"CV51"7;
"VSS_CV48"
$PN"CV48"7;
"VSS_CV31"
$PN"CV31"7;
"VSS_CV28"
$PN"CV28"7;
"VSS_CV25"
$PN"CV25"7;
"VSS_CV22"
$PN"CV22"7;
"VSS_CV19"
$PN"CV19"7;
"VSS_CV17"
$PN"CV17"7;
"VSS_CV3"
$PN"CV3"8;
"VSS_CU75"
$PN"CU75"8;
"VSS_CU72"
$PN"CU72"8;
"VSS_CU70"
$PN"CU70"8;
"VSS_CU68"
$PN"CU68"8;
"VSS_CU65"
$PN"CU65"8;
"VSS_CU54"
$PN"CU54"8;
"VSS_CU51"
$PN"CU51"8;
"VSS_CU48"
$PN"CU48"8;
"VSS_CU45"
$PN"CU45"8;
"VSS_CU42"
$PN"CU42"8;
"VSS_CU34"
$PN"CU34"8;
"VSS_CU31"
$PN"CU31"8;
"VSS_CU20"
$PN"CU20"8;
"VSS_CU18"
$PN"CU18"8;
"VSS_CU15"
$PN"CU15"8;
"VSS_CU13"
$PN"CU13"8;
"VSS_CU11"
$PN"CU11"8;
"VSS_CU8"
$PN"CU8"8;
"VSS_CU6"
$PN"CU6"8;
"VSS_CU4"
$PN"CU4"8;
"VSS_CT68"
$PN"CT68"8;
"VSS_CT66"
$PN"CT66"8;
"VSS_CT61"
$PN"CT61"8;
"VSS_CT59"
$PN"CT59"8;
"VSS_CT53"
$PN"CT53"8;
"VSS_CT51"
$PN"CT51"8;
"VSS_CT50"
$PN"CT50"8;
"VSS_CT49"
$PN"CT49"8;
"VSS_CT47"
$PN"CT47"8;
"VSS_CT46"
$PN"CT46"8;
"VSS_CT45"
$PN"CT45"8;
"VSS_CT44"
$PN"CT44"8;
"VSS_CT43"
$PN"CT43"8;
"VSS_CT42"
$PN"CT42"8;
"VSS_CT39"
$PN"CT39"8;
"VSS_CT37"
$PN"CT37"8;
"VSS_CT34"
$PN"CT34"8;
"VSS_CT33"
$PN"CT33"8;
"VSS_CT32"
$PN"CT32"8;
"VSS_CT31"
$PN"CT31"8;
"VSS_CT30"
$PN"CT30"8;
"VSS_CT29"
$PN"CT29"8;
"VSS_CT28"
$PN"CT28"8;
"VSS_CT27"
$PN"CT27"8;
"VSS_CT26"
$PN"CT26"8;
"VSS_CT25"
$PN"CT25"8;
"VSS_CT24"
$PN"CT24"8;
"VSS_CT23"
$PN"CT23"8;
"VSS_CT17"
$PN"CT17"8;
"VSS_CR72"
$PN"CR72"8;
"VSS_CR70"
$PN"CR70"8;
"VSS_CR68"
$PN"CR68"8;
"VSS_CR65"
$PN"CR65"8;
"VSS_CR63"
$PN"CR63"8;
"VSS_CR61"
$PN"CR61"8;
"VSS_CR45"
$PN"CR45"8;
"VSS_CR42"
$PN"CR42"8;
"VSS_CR41"
$PN"CR41"8;
"VSS_CR40"
$PN"CR40"8;
"VSS_CR36"
$PN"CR36"8;
"VSS_CR35"
$PN"CR35"8;
"VSS_CR20"
$PN"CR20"8;
"VSS_CR18"
$PN"CR18"8;
"VSS_CR15"
$PN"CR15"8;
"VSS_CR13"
$PN"CR13"8;
"VSS_CR11"
$PN"CR11"8;
"VSS_CR8"
$PN"CR8"8;
"VSS_CP68"
$PN"CP68"8;
"VSS_CP66"
$PN"CP66"8;
"VSS_CP64"
$PN"CP64"8;
"VSS_CP61"
$PN"CP61"8;
"VSS_CP59"
$PN"CP59"8;
"VSS_CP57"
$PN"CP57"8;
"VSS_CP39"
$PN"CP39"8;
"VSS_CP37"
$PN"CP37"8;
"VSS_CP34"
$PN"CP34"8;
"VSS_CP31"
$PN"CP31"8;
"VSS_CP28"
$PN"CP28"8;
"VSS_CP25"
$PN"CP25"8;
"VSS_DA54"
$PN"DA54"7;
"VSS_DA51"
$PN"DA51"7;
"VSS_DA48"
$PN"DA48"7;
"VSS_DA45"
$PN"DA45"7;
"VSS_DA20"
$PN"DA20"7;
"VSS_DA18"
$PN"DA18"7;
"VSS_DA15"
$PN"DA15"7;
"VSS_DA13"
$PN"DA13"7;
"VSS_CY68"
$PN"CY68"7;
"VSS_CY66"
$PN"CY66"7;
"VSS_CY64"
$PN"CY64"7;
"VSS_CY48"
$PN"CY48"7;
"VSS_CY47"
$PN"CY47"7;
"VSS_CY32"
$PN"CY32"7;
"VSS_CW34"
$PN"CW34"7;
"VSS_CW31"
$PN"CW31"7;
"VSS_CW28"
$PN"CW28"7;
"VSS_CW25"
$PN"CW25"7;
"VSS_CW22"
$PN"CW22"7;
"VSS_CV73"
$PN"CV73"7;
"VSS_CV71"
$PN"CV71"7;
"VSS_CV68"
$PN"CV68"7;
"VSS_CV66"
$PN"CV66"7;
"VSS_CV64"
$PN"CV64"7;
"VSS_CV45"
$PN"CV45"7;
"VSS_CV42"
$PN"CV42"7;
"VSS_CV39"
$PN"CV39"7;
"VSS_CV37"
$PN"CV37"7;
"VSS_CV34"
$PN"CV34"7;
"VSS_CV15"
$PN"CV15"7;
"VSS_CV12"
$PN"CV12"7;
"VSS_CV10"
$PN"CV10"7;
"VSS_CV8"
$PN"CV8"8;
"VSS_CV5"
$PN"CV5"8;
"VSS_CU63"
$PN"CU63"8;
"VSS_CU61"
$PN"CU61"8;
"VSS_CU56"
$PN"CU56"8;
"VSS_CU28"
$PN"CU28"8;
"VSS_CU25"
$PN"CU25"8;
"VSS_CU22"
$PN"CU22"8;
"VSS_CU1"
$PN"CU1"8;
"VSS_CT73"
$PN"CT73"8;
"VSS_CT48"
$PN"CT48"8;
"VSS_CT15"
$PN"CT15"8;
"VSS_CT10"
$PN"CT10"8;
"VSS_CT8"
$PN"CT8"8;
"VSS_CT3"
$PN"CT3"8;
"VSS_CR75"
$PN"CR75"8;
"VSS_CR58"
$PN"CR58"8;
"VSS_CR56"
$PN"CR56"8;
"VSS_CR54"
$PN"CR54"8;
"VSS_CR51"
$PN"CR51"8;
"VSS_CR48"
$PN"CR48"8;
"VSS_CR34"
$PN"CR34"8;
"VSS_CR31"
$PN"CR31"8;
"VSS_CR28"
$PN"CR28"8;
"VSS_CR25"
$PN"CR25"8;
"VSS_CR22"
$PN"CR22"8;
"VSS_CR6"
$PN"CR6"8;
"VSS_CR4"
$PN"CR4"8;
"VSS_CR1"
$PN"CR1"8;
"VSS_CP73"
$PN"CP73"8;
"VSS_CP71"
$PN"CP71"8;
"VSS_CP54"
$PN"CP54"8;
"VSS_CP51"
$PN"CP51"8;
"VSS_CP48"
$PN"CP48"8;
"VSS_CP45"
$PN"CP45"8;
"VSS_CP42"
$PN"CP42"8;
"VSS_CP22"
$PN"CP22"8;
%"UNIVERSAL_GND"
"1","(-7050,425)","0","pure_quanta_power","I17";
;
CDS_LIB"pure_quanta_power"
HDL_POWER"GND";
"A"2;
%"UNIVERSAL_GND"
"1","(-8500,400)","0","pure_quanta_power","I18";
;
CDS_LIB"pure_quanta_power"
HDL_POWER"GND";
"A"1;
%"UNIVERSAL_GND"
"1","(-6475,425)","0","pure_quanta_power","I19";
;
CDS_LIB"pure_quanta_power"
HDL_POWER"GND";
"A"3;
%"UNIVERSAL_GND"
"1","(-5025,425)","0","pure_quanta_power","I20";
;
CDS_LIB"pure_quanta_power"
HDL_POWER"GND";
"A"4;
%"UNIVERSAL_GND"
"1","(-4400,425)","0","pure_quanta_power","I21";
;
CDS_LIB"pure_quanta_power"
HDL_POWER"GND";
"A"5;
%"UNIVERSAL_GND"
"1","(-2950,400)","0","pure_quanta_power","I22";
;
CDS_LIB"pure_quanta_power"
HDL_POWER"GND";
"A"6;
%"UNIVERSAL_GND"
"1","(-875,400)","0","pure_quanta_power","I23";
;
CDS_LIB"pure_quanta_power"
HDL_POWER"GND";
"A"8;
%"UNIVERSAL_GND"
"1","(-2325,400)","0","pure_quanta_power","I24";
;
CDS_LIB"pure_quanta_power"
HDL_POWER"GND";
"A"7;
END.
